# S9S_MB_2U (Grand Teton) — schematic netlist excerpt (pin names and nets, part order shuffled) for the footprints in the layout excerpt that follows; sources: Cadence DE-HDL packaged netlist, KiCad conversion of 03242023_DA0F0TMBIJ0_F0T_Motherboard_J_brd_V01_OCP.brd

PR326  Q_RES  8.87K 1% EMPTY  pkg 0402LF  page 285 : A = PVCCIN_CPU1_LSET1 ; B = GND

U134  74LVC2G07DW7  74LVC2G07DW-7 IC  pkg SOT363_0-65_2X1-25XC  page 191
  \1a\  = RST_SMB_E1S_N
  GND  = GND
  \2a\  = RST_SMB_E1S_N
  \2y\  = SMB_PCIE_E1S_ISO_EN_R2
  VCC  = P3V3_AUX
  \1y\  = RST_SMB_BUF_E1S_0_N

(kicad_pcb
	(version 20260206)
	(generator "pcbnew")
	(generator_version "10.0")
	(general
		(thickness 1.6)
		(legacy_teardrops no)
	)
	(paper "A4")
	(title_block
		(title "03242023_DA0F0TMBIJ0_F0T_Motherboard_J_brd_V01_OCP.brd")
		(comment 1 "Grand Teton / footprints 2412-2413 of 6105")
	)
	(layers
		(0 "F.Cu" signal "TOP")
		(4 "In1.Cu" signal "GND")
		(6 "In2.Cu" signal "IN1")
		(8 "In3.Cu" signal "GND1")
		(10 "In4.Cu" signal "IN2")
		(12 "In5.Cu" signal "GND2")
		(14 "In6.Cu" signal "IN3")
		(16 "In7.Cu" signal "GND3")
		(18 "In8.Cu" signal "VCC")
		(20 "In9.Cu" signal "VCC1")
		(22 "In10.Cu" signal "GND4")
		(24 "In11.Cu" signal "IN4")
		(26 "In12.Cu" signal "GND5")
		(28 "In13.Cu" signal "IN5")
		(30 "In14.Cu" signal "GND6")
		(32 "In15.Cu" signal "IN6")
		(34 "In16.Cu" signal "GND7")
		(2 "B.Cu" signal "BOTTOM")
		(9 "F.Adhes" user "F.Adhesive")
		(11 "B.Adhes" user "B.Adhesive")
		(13 "F.Paste" user "Package Geometry/Pastemask Top")
		(15 "B.Paste" user "Package Geometry/Pastemask Bottom")
		(5 "F.SilkS" user "Ref Des/Silkscreen Top")
		(7 "B.SilkS" user "Ref Des/Silkscreen Bottom")
		(1 "F.Mask" user "Board Geometry/Soldermask Top")
		(3 "B.Mask" user "Board Geometry/Soldermask Bottom")
		(17 "Dwgs.User" user "User.Drawings")
		(19 "Cmts.User" user "User.Comments")
		(21 "Eco1.User" user "User.Eco1")
		(23 "Eco2.User" user "User.Eco2")
		(25 "Edge.Cuts" user "Board Geometry/Outline")
		(27 "Margin" user)
		(31 "F.CrtYd" user "Package Geometry/Place Bound Top")
		(29 "B.CrtYd" user "Package Geometry/Place Bound Bottom")
		(35 "F.Fab" user "Ref Des/Assembly Top")
		(33 "B.Fab" user "Ref Des/Assembly Bottom")
	)
	(footprint ""
		(layer "F.Cu")
		(at 95.706438 -338.86013)
		(property "Reference" "PR326"
			(at 0 0 0)
			(layer "F.SilkS")
			(hide yes)
			(effects
				(font
					(size 1.27 1.27)
				)
			)
		)
		(property "Value" ""
			(at 0 0 0)
			(layer "F.Fab")
			(effects
				(font
					(size 1.27 1.27)
				)
			)
		)
		(duplicate_pad_numbers_are_jumpers no)
		(fp_line
			(start -0.7874 -0.4064)
			(end 0.7874 -0.4064)
			(stroke
				(width 0.1524)
				(type default)
			)
			(layer "F.SilkS")
		)
		(fp_line
			(start -0.7874 0.4064)
			(end -0.7874 -0.4064)
			(stroke
				(width 0.1524)
				(type default)
			)
			(layer "F.SilkS")
		)
		(fp_line
			(start 0.7874 -0.4064)
			(end 0.7874 0.4064)
			(stroke
				(width 0.1524)
				(type default)
			)
			(layer "F.SilkS")
		)
		(fp_line
			(start 0.7874 0.4064)
			(end -0.7874 0.4064)
			(stroke
				(width 0.1524)
				(type default)
			)
			(layer "F.SilkS")
		)
		(fp_line
			(start -0.67945 -0.305054)
			(end -0.12065 -0.305054)
			(stroke
				(width 0.1)
				(type default)
			)
			(layer "F.Fab")
		)
		(fp_line
			(start -0.67945 0.3048)
			(end -0.67945 -0.305054)
			(stroke
				(width 0.1)
				(type default)
			)
			(layer "F.Fab")
		)
		(fp_line
			(start -0.12065 -0.305054)
			(end -0.12065 -0.2794)
			(stroke
				(width 0.1)
				(type default)
			)
			(layer "F.Fab")
		)
		(fp_line
			(start -0.12065 -0.2794)
			(end 0.12065 -0.2794)
			(stroke
				(width 0.1)
				(type default)
			)
			(layer "F.Fab")
		)
		(fp_line
			(start -0.12065 0.2794)
			(end -0.12065 0.3048)
			(stroke
				(width 0.1)
				(type default)
			)
			(layer "F.Fab")
		)
		(fp_line
			(start -0.12065 0.3048)
			(end -0.67945 0.3048)
			(stroke
				(width 0.1)
				(type default)
			)
			(layer "F.Fab")
		)
		(fp_line
			(start 0.120396 0.2794)
			(end -0.12065 0.2794)
			(stroke
				(width 0.1)
				(type default)
			)
			(layer "F.Fab")
		)
		(fp_line
			(start 0.120396 0.3048)
			(end 0.120396 0.2794)
			(stroke
				(width 0.1)
				(type default)
			)
			(layer "F.Fab")
		)
		(fp_line
			(start 0.12065 -0.3048)
			(end 0.67945 -0.3048)
			(stroke
				(width 0.1)
				(type default)
			)
			(layer "F.Fab")
		)
		(fp_line
			(start 0.12065 -0.2794)
			(end 0.12065 -0.3048)
			(stroke
				(width 0.1)
				(type default)
			)
			(layer "F.Fab")
		)
		(fp_line
			(start 0.67945 -0.3048)
			(end 0.67945 0.3048)
			(stroke
				(width 0.1)
				(type default)
			)
			(layer "F.Fab")
		)
		(fp_line
			(start 0.67945 0.3048)
			(end 0.120396 0.3048)
			(stroke
				(width 0.1)
				(type default)
			)
			(layer "F.Fab")
		)
		(pad "1" smd circle
			(at -0.40005 0)
			(size 0 0)
			(layers "F.Cu" "F.Mask" "F.Paste")
			(net "PVCCIN_CPU1_LSET1")
		)
		(pad "2" smd circle
			(at 0.40005 0)
			(size 0 0)
			(layers "F.Cu" "F.Mask" "F.Paste")
			(net "GND")
		)
	)
	(footprint ""
		(layer "F.Cu")
		(at 155.742386 -64.761364)
		(property "Reference" "U134"
			(at -1.4732 2.041652 0)
			(unlocked yes)
			(layer "F.SilkS")
			(effects
				(font
					(size 0.7874 0.5842)
					(thickness 0.1524)
				)
				(justify left)
			)
		)
		(property "Value" ""
			(at 0 0 0)
			(layer "F.Fab")
			(effects
				(font
					(size 1.27 1.27)
				)
			)
		)
		(duplicate_pad_numbers_are_jumpers no)
		(fp_line
			(start -1.38176 -1.100074)
			(end -1.38176 1.100074)
			(stroke
				(width 0.1524)
				(type default)
			)
			(layer "F.SilkS")
		)
		(fp_line
			(start -1.38176 1.100074)
			(end 1.38176 1.100074)
			(stroke
				(width 0.1524)
				(type default)
			)
			(layer "F.SilkS")
		)
		(fp_line
			(start -0.592074 -1.100074)
			(end -1.38176 -1.100074)
			(stroke
				(width 0.1524)
				(type default)
			)
			(layer "F.SilkS")
		)
		(fp_line
			(start 0 -0.508)
			(end -0.592074 -1.100074)
			(stroke
				(width 0.1524)
				(type default)
			)
			(layer "F.SilkS")
		)
		(fp_line
			(start 0.592074 -1.100074)
			(end 0 -0.508)
			(stroke
				(width 0.1524)
				(type default)
			)
			(layer "F.SilkS")
		)
		(fp_line
			(start 1.38176 -1.100074)
			(end 0.592074 -1.100074)
			(stroke
				(width 0.1524)
				(type default)
			)
			(layer "F.SilkS")
		)
		(fp_line
			(start 1.38176 1.100074)
			(end 1.38176 -1.100074)
			(stroke
				(width 0.1524)
				(type default)
			)
			(layer "F.SilkS")
		)
		(fp_poly
			(pts
				(xy -0.989584 -1.349248) (xy -1.209802 -1.789938) (xy -0.769366 -1.789938)
			)
			(stroke
				(width 0)
				(type default)
			)
			(fill yes)
			(layer "F.SilkS")
		)
		(fp_line
			(start -0.674878 -1.100074)
			(end -0.674878 1.100074)
			(stroke
				(width 0.1)
				(type default)
			)
			(layer "F.Fab")
		)
		(fp_line
			(start -0.674878 1.100074)
			(end 0.674878 1.100074)
			(stroke
				(width 0.1)
				(type default)
			)
			(layer "F.Fab")
		)
		(fp_line
			(start 0.674878 -1.100074)
			(end -0.674878 -1.100074)
			(stroke
				(width 0.1)
				(type default)
			)
			(layer "F.Fab")
		)
		(fp_line
			(start 0.674878 1.100074)
			(end 0.674878 -1.100074)
			(stroke
				(width 0.1)
				(type default)
			)
			(layer "F.Fab")
		)
		(fp_poly
			(pts
				(xy -1.9431 -0.870204) (xy -1.50241 -0.649986) (xy -1.9431 -0.429768)
			)
			(stroke
				(width 0)
				(type default)
			)
			(fill yes)
			(layer "F.Fab")
		)
		(pad "1" smd rect
			(at -0.94996 -0.649986 270)
			(size 0.4318 0.6096)
			(layers "F.Cu" "F.Mask" "F.Paste")
			(net "RST_SMB_E1S_N")
		)
		(pad "2" smd rect
			(at -0.94996 0 270)
			(size 0.4318 0.6096)
			(layers "F.Cu" "F.Mask" "F.Paste")
			(net "GND")
		)
		(pad "3" smd rect
			(at -0.94996 0.649986 270)
			(size 0.4318 0.6096)
			(layers "F.Cu" "F.Mask" "F.Paste")
			(net "RST_SMB_E1S_N")
		)
		(pad "4" smd rect
			(at 0.94996 0.649986 270)
			(size 0.4318 0.6096)
			(layers "F.Cu" "F.Mask" "F.Paste")
			(net "SMB_PCIE_E1S_ISO_EN_R2")
		)
		(pad "5" smd rect
			(at 0.94996 0 270)
			(size 0.4318 0.6096)
			(layers "F.Cu" "F.Mask" "F.Paste")
			(net "P3V3_AUX")
		)
		(pad "6" smd rect
			(at 0.94996 -0.649986 270)
			(size 0.4318 0.6096)
			(layers "F.Cu" "F.Mask" "F.Paste")
			(net "RST_SMB_BUF_E1S_0_N")
		)
	)
)
